# T6G (Grand Teton) — schematic netlist excerpt (pin names and nets, part order shuffled) for the footprints in the layout excerpt that follows; sources: Cadence DE-HDL packaged netlist, KiCad conversion of 04192023_DAF0TMB3IC0_F0TG_MB_C_brd_V02_OCP.brd

PU48  ISL99390FRZTR5935  ISL99390FRZ-TR5935 IC  pkg QFN21_6X5XB  page 196
  VOS  = PVDDCR_CPU0_P0_VOS5
  AGND  = GND
  VCC  = PVDDCR_CPU0_P0_VCC5
  PVCC  = PVDDCR_CPU0_P0_PVCC
  PGND1  = GND
  GL1  = NC_PVDDCR_CPU0_P0_GL1_5
  PGND2  = GND
  SW  = SW_PVDDCR_CPU0_P0_SW5
  VIN1  = SW_P12V_AUX_PVDDCR_CPU0_P0_FLT
  VIN2  = SW_P12V_AUX_PVDDCR_CPU0_P0_FLT
  DNC  = NC_PVDDCR_CPU0_P0_DNC5
  PHASE  = SW_PVDDCR_CPU0_P0_PH5
  BOOT  = SW_PVDDCR_CPU0_P0_BOOT5
  PWM  = PVDDCR_CPU0_P0_PWM5
  EN  = PVDDCR_CPU0_P0_VCC5
  TOUT_FLT  = PVDDCR_CPU0_P0_TEMP0
  LSET  = PVDDCR_CPU0_P0_LSET5
  IOUT  = PVDDCR_CPU0_P0_IMON5
  REFIN  = PVDDCR_CPU0_P0_VCCS
  PGND3  = GND
  GL2  = NC_PVDDCR_CPU0_P0_GL2_5

(kicad_pcb
	(version 20260206)
	(generator "pcbnew")
	(generator_version "10.0")
	(general
		(thickness 1.6)
		(legacy_teardrops no)
	)
	(paper "A4")
	(title_block
		(title "04192023_DAF0TMB3IC0_F0TG_MB_C_brd_V02_OCP.brd")
		(comment 1 "Grand Teton / footprints 2134-2134 of 8354")
	)
	(layers
		(0 "F.Cu" signal "TOP")
		(4 "In1.Cu" signal "GND")
		(6 "In2.Cu" signal "IN1")
		(8 "In3.Cu" signal "GND1")
		(10 "In4.Cu" signal "IN2")
		(12 "In5.Cu" signal "GND2")
		(14 "In6.Cu" signal "IN3")
		(16 "In7.Cu" signal "GND3")
		(18 "In8.Cu" signal "VCC")
		(20 "In9.Cu" signal "VCC1")
		(22 "In10.Cu" signal "GND4")
		(24 "In11.Cu" signal "IN4")
		(26 "In12.Cu" signal "GND5")
		(28 "In13.Cu" signal "IN5")
		(30 "In14.Cu" signal "GND6")
		(32 "In15.Cu" signal "IN6")
		(34 "In16.Cu" signal "GND7")
		(2 "B.Cu" signal "BOTTOM")
		(9 "F.Adhes" user "F.Adhesive")
		(11 "B.Adhes" user "B.Adhesive")
		(13 "F.Paste" user "Package Geometry/Pastemask Top")
		(15 "B.Paste" user "Package Geometry/Pastemask Bottom")
		(5 "F.SilkS" user "Ref Des/Silkscreen Top")
		(7 "B.SilkS" user "Ref Des/Silkscreen Bottom")
		(1 "F.Mask" user "Board Geometry/Soldermask Top")
		(3 "B.Mask" user "Board Geometry/Soldermask Bottom")
		(17 "Dwgs.User" user "User.Drawings")
		(19 "Cmts.User" user "User.Comments")
		(21 "Eco1.User" user "User.Eco1")
		(23 "Eco2.User" user "User.Eco2")
		(25 "Edge.Cuts" user "Board Geometry/Outline")
		(27 "Margin" user)
		(31 "F.CrtYd" user "Package Geometry/Place Bound Top")
		(29 "B.CrtYd" user "Package Geometry/Place Bound Bottom")
		(35 "F.Fab" user "Ref Des/Assembly Top")
		(33 "B.Fab" user "Ref Des/Assembly Bottom")
	)
	(footprint ""
		(layer "F.Cu")
		(at 356.033578 -169.495978 180)
		(property "Reference" "PU48"
			(at 0.486156 -7.523226 0)
			(unlocked yes)
			(layer "F.SilkS")
			(effects
				(font
					(size 0.7874 0.5842)
					(thickness 0.1524)
				)
				(justify left)
			)
		)
		(property "Value" ""
			(at 0 0 180)
			(layer "F.Fab")
			(effects
				(font
					(size 1.27 1.27)
				)
			)
		)
		(duplicate_pad_numbers_are_jumpers no)
		(fp_line
			(start 2.500122 2.999994)
			(end 2.2987 2.999994)
			(stroke
				(width 0.1524)
				(type default)
			)
			(layer "F.SilkS")
		)
		(fp_line
			(start 2.500122 2.339594)
			(end 2.500122 2.999994)
			(stroke
				(width 0.1524)
				(type default)
			)
			(layer "F.SilkS")
		)
		(fp_line
			(start 2.500122 -2.999994)
			(end 2.500122 -2.44348)
			(stroke
				(width 0.1524)
				(type default)
			)
			(layer "F.SilkS")
		)
		(fp_line
			(start 2.31394 -2.999994)
			(end 2.500122 -2.999994)
			(stroke
				(width 0.1524)
				(type default)
			)
			(layer "F.SilkS")
		)
		(fp_line
			(start -2.2987 2.999994)
			(end -2.500122 2.999994)
			(stroke
				(width 0.1524)
				(type default)
			)
			(layer "F.SilkS")
		)
		(fp_line
			(start -2.500122 2.999994)
			(end -2.500122 2.339594)
			(stroke
				(width 0.1524)
				(type default)
			)
			(layer "F.SilkS")
		)
		(fp_line
			(start -2.500122 0.6604)
			(end -2.500122 0.229108)
			(stroke
				(width 0.1524)
				(type default)
			)
			(layer "F.SilkS")
		)
		(fp_line
			(start -2.500122 -2.529078)
			(end -2.500122 -2.999994)
			(stroke
				(width 0.1524)
				(type default)
			)
			(layer "F.SilkS")
		)
		(fp_line
			(start -2.500122 -2.999994)
			(end -2.24409 -2.999994)
			(stroke
				(width 0.1524)
				(type default)
			)
			(layer "F.SilkS")
		)
		(fp_poly
			(pts
				(xy -2.712466 -2.468372) (xy -3.43662 -2.709672) (xy -2.95402 -3.192526)
			)
			(stroke
				(width 0)
				(type default)
			)
			(fill yes)
			(layer "F.SilkS")
		)
		(fp_line
			(start 2.500122 2.999994)
			(end -2.500122 2.999994)
			(stroke
				(width 0.1)
				(type default)
			)
			(layer "F.Fab")
		)
		(fp_line
			(start 2.500122 -2.999994)
			(end 2.500122 2.999994)
			(stroke
				(width 0.1)
				(type default)
			)
			(layer "F.Fab")
		)
		(fp_line
			(start -2.500122 2.999994)
			(end -2.500122 -2.999994)
			(stroke
				(width 0.1)
				(type default)
			)
			(layer "F.Fab")
		)
		(fp_line
			(start -2.500122 -2.999994)
			(end 2.500122 -2.999994)
			(stroke
				(width 0.1)
				(type default)
			)
			(layer "F.Fab")
		)
		(fp_poly
			(pts
				(xy -4.218432 -2.783078) (xy -4.218432 -1.767078) (xy -3.202432 -2.275078)
			)
			(stroke
				(width 0)
				(type default)
			)
			(fill yes)
			(layer "F.Fab")
		)
		(pad "1" smd rect
			(at -2.400046 -2.275078 270)
			(size 0.2286 0.6096)
			(layers "F.Cu" "F.Mask" "F.Paste")
			(net "PVDDCR_CPU0_P0_VOS5")
		)
		(pad "2" smd rect
			(at -2.400046 -1.82499 270)
			(size 0.2286 0.6096)
			(layers "F.Cu" "F.Mask" "F.Paste")
			(net "GND")
		)
		(pad "3" smd rect
			(at -2.400046 -1.374902 270)
			(size 0.2286 0.6096)
			(layers "F.Cu" "F.Mask" "F.Paste")
			(net "PVDDCR_CPU0_P0_VCC5")
		)
		(pad "4" smd rect
			(at -2.400046 -0.925068 270)
			(size 0.2286 0.6096)
			(layers "F.Cu" "F.Mask" "F.Paste")
			(net "PVDDCR_CPU0_P0_PVCC")
		)
		(pad "5" smd rect
			(at -2.400046 -0.47498 270)
			(size 0.2286 0.6096)
			(layers "F.Cu" "F.Mask" "F.Paste")
			(net "GND")
		)
		(pad "6" smd rect
			(at -2.400046 -0.024892 270)
			(size 0.2286 0.6096)
			(layers "F.Cu" "F.Mask" "F.Paste")
			(net "NC_PVDDCR_CPU0_P0_GL1_5")
		)
		(pad "7_9-20_24" smd circle
			(at 0 1.150112 270)
			(size 0 0)
			(layers "F.Cu" "F.Mask" "F.Paste")
			(net "GND")
		)
		(pad "10_19" smd rect
			(at 0 2.899918 270)
			(size 0.6096 4.318)
			(layers "F.Cu" "F.Mask" "F.Paste")
			(net "SW_PVDDCR_CPU0_P0_SW5")
		)
		(pad "25_29" smd rect
			(at 1.549908 -1.279906 90)
			(size 2.0574 2.3114)
			(layers "F.Cu" "F.Mask" "F.Paste")
			(net "SW_P12V_AUX_PVDDCR_CPU0_P0_FLT")
		)
		(pad "30" smd rect
			(at 2.05994 -2.899918 180)
			(size 0.2286 0.6096)
			(layers "F.Cu" "F.Mask" "F.Paste")
			(net "SW_P12V_AUX_PVDDCR_CPU0_P0_FLT")
		)
		(pad "31" smd rect
			(at 1.610106 -2.899918 180)
			(size 0.2286 0.6096)
			(layers "F.Cu" "F.Mask" "F.Paste")
			(net "NC_PVDDCR_CPU0_P0_DNC5")
		)
		(pad "32" smd rect
			(at 1.160018 -2.899918 180)
			(size 0.2286 0.6096)
			(layers "F.Cu" "F.Mask" "F.Paste")
			(net "SW_PVDDCR_CPU0_P0_PH5")
		)
		(pad "33" smd rect
			(at 0.70993 -2.899918 180)
			(size 0.2286 0.6096)
			(layers "F.Cu" "F.Mask" "F.Paste")
			(net "SW_PVDDCR_CPU0_P0_BOOT5")
		)
		(pad "34" smd rect
			(at 0.260096 -2.899918 180)
			(size 0.2286 0.6096)
			(layers "F.Cu" "F.Mask" "F.Paste")
			(net "PVDDCR_CPU0_P0_PWM5")
		)
		(pad "35" smd rect
			(at -0.189992 -2.899918 180)
			(size 0.2286 0.6096)
			(layers "F.Cu" "F.Mask" "F.Paste")
			(net "PVDDCR_CPU0_P0_VCC5")
		)
		(pad "36" smd rect
			(at -0.64008 -2.899918 180)
			(size 0.2286 0.6096)
			(layers "F.Cu" "F.Mask" "F.Paste")
			(net "PVDDCR_CPU0_P0_TEMP0")
		)
		(pad "37" smd rect
			(at -1.089914 -2.899918 180)
			(size 0.2286 0.6096)
			(layers "F.Cu" "F.Mask" "F.Paste")
			(net "PVDDCR_CPU0_P0_LSET5")
		)
		(pad "38" smd rect
			(at -1.540002 -2.899918 180)
			(size 0.2286 0.6096)
			(layers "F.Cu" "F.Mask" "F.Paste")
			(net "PVDDCR_CPU0_P0_IMON5")
		)
		(pad "39" smd rect
			(at -1.99009 -2.899918 180)
			(size 0.2286 0.6096)
			(layers "F.Cu" "F.Mask" "F.Paste")
			(net "PVDDCR_CPU0_P0_VCCS")
		)
		(pad "40" smd rect
			(at -0.87503 -1.27508 180)
			(size 1.7526 1.9558)
			(layers "F.Cu" "F.Mask" "F.Paste")
			(net "GND")
		)
		(pad "41" smd rect
			(at -1.525016 0.249936 90)
			(size 0.3048 0.4572)
			(layers "F.Cu" "F.Mask" "F.Paste")
			(net "NC_PVDDCR_CPU0_P0_GL2_5")
		)
		(zone
			(layer "F.Cu")
			(hatch none 0.5)
			(connect_pads
				(clearance 0)
			)
			(min_thickness 0.25)
			(keepout
				(tracks not_allowed)
				(vias allowed)
				(pads allowed)
				(copperpour not_allowed)
				(footprints allowed)
			)
			(placement
				(enabled no)
				(sheetname "")
			)
			(fill
				(thermal_gap 0.5)
				(thermal_bridge_width 0.5)
				(island_removal_mode 0)
			)
			(polygon
				(pts
					(xy 358.5337 -172.070776) (xy 358.5337 -171.746672) (xy 353.533456 -171.746672) (xy 353.533456 -172.076618)
					(xy 353.823778 -172.076618) (xy 353.823778 -172.040296) (xy 358.243378 -172.040296) (xy 358.243378 -172.070776)
				)
			)
		)
		(zone
			(layer "F.Cu")
			(hatch none 0.5)
			(connect_pads
				(clearance 0)
			)
			(min_thickness 0.25)
			(keepout
				(tracks not_allowed)
				(vias allowed)
				(pads allowed)
				(copperpour not_allowed)
				(footprints allowed)
			)
			(placement
				(enabled no)
				(sheetname "")
			)
			(fill
				(thermal_gap 0.5)
				(thermal_bridge_width 0.5)
				(island_removal_mode 0)
			)
			(polygon
				(pts
					(xy 355.981508 -169.249598) (xy 355.981508 -167.192198) (xy 357.835708 -167.192198) (xy 357.835708 -167.433244)
					(xy 358.078024 -167.433244) (xy 358.078024 -166.95166) (xy 354.210112 -166.95166) (xy 354.210112 -167.136572)
					(xy 355.69017 -167.136572) (xy 355.69017 -169.295572) (xy 353.533456 -169.295572) (xy 353.533456 -169.545254)
					(xy 355.698806 -169.545254) (xy 355.981508 -169.262552)
				)
			)
		)
	)
)
